# T6G (Grand Teton) — schematic netlist excerpt (pin names and nets, part order shuffled) for the footprints in the layout excerpt that follows; sources: Cadence DE-HDL packaged netlist, KiCad conversion of 04192023_DAF0TMB3IC0_F0TG_MB_C_brd_V02_OCP.brd

R3601  Q_RES  0 5% CHIP  pkg 0402LF  page 236 : A = SMB_INA230_1_3V3AUX_SDA_R ; B = SMB_INA230_1_3V3AUX_SDA_R1
C77  Q_CAP  10UF 6.3V 20% X6S  pkg C0402  page 182 : A = P3V3_9ZXL045_P0_VDDR ; B = GND

(kicad_pcb
	(version 20260206)
	(generator "pcbnew")
	(generator_version "10.0")
	(general
		(thickness 1.6)
		(legacy_teardrops no)
	)
	(paper "A4")
	(title_block
		(title "04192023_DAF0TMB3IC0_F0TG_MB_C_brd_V02_OCP.brd")
		(comment 1 "Grand Teton / footprints 3913-3914 of 8354")
	)
	(layers
		(0 "F.Cu" signal "TOP")
		(4 "In1.Cu" signal "GND")
		(6 "In2.Cu" signal "IN1")
		(8 "In3.Cu" signal "GND1")
		(10 "In4.Cu" signal "IN2")
		(12 "In5.Cu" signal "GND2")
		(14 "In6.Cu" signal "IN3")
		(16 "In7.Cu" signal "GND3")
		(18 "In8.Cu" signal "VCC")
		(20 "In9.Cu" signal "VCC1")
		(22 "In10.Cu" signal "GND4")
		(24 "In11.Cu" signal "IN4")
		(26 "In12.Cu" signal "GND5")
		(28 "In13.Cu" signal "IN5")
		(30 "In14.Cu" signal "GND6")
		(32 "In15.Cu" signal "IN6")
		(34 "In16.Cu" signal "GND7")
		(2 "B.Cu" signal "BOTTOM")
		(9 "F.Adhes" user "F.Adhesive")
		(11 "B.Adhes" user "B.Adhesive")
		(13 "F.Paste" user "Package Geometry/Pastemask Top")
		(15 "B.Paste" user "Package Geometry/Pastemask Bottom")
		(5 "F.SilkS" user "Ref Des/Silkscreen Top")
		(7 "B.SilkS" user "Ref Des/Silkscreen Bottom")
		(1 "F.Mask" user "Board Geometry/Soldermask Top")
		(3 "B.Mask" user "Board Geometry/Soldermask Bottom")
		(17 "Dwgs.User" user "User.Drawings")
		(19 "Cmts.User" user "User.Comments")
		(21 "Eco1.User" user "User.Eco1")
		(23 "Eco2.User" user "User.Eco2")
		(25 "Edge.Cuts" user "Board Geometry/Outline")
		(27 "Margin" user)
		(31 "F.CrtYd" user "Package Geometry/Place Bound Top")
		(29 "B.CrtYd" user "Package Geometry/Place Bound Bottom")
		(35 "F.Fab" user "Ref Des/Assembly Top")
		(33 "B.Fab" user "Ref Des/Assembly Bottom")
	)
	(footprint ""
		(layer "F.Cu")
		(at 280.67 -426.212 90)
		(property "Reference" "C77"
			(at 0 0 90)
			(layer "F.SilkS")
			(hide yes)
			(effects
				(font
					(size 1.27 1.27)
				)
			)
		)
		(property "Value" ""
			(at 0 0 90)
			(layer "F.Fab")
			(effects
				(font
					(size 1.27 1.27)
				)
			)
		)
		(duplicate_pad_numbers_are_jumpers no)
		(fp_line
			(start 0.7874 -0.4064)
			(end 0.7874 0.4064)
			(stroke
				(width 0.1524)
				(type default)
			)
			(layer "F.SilkS")
		)
		(fp_line
			(start -0.7874 -0.4064)
			(end 0.7874 -0.4064)
			(stroke
				(width 0.1524)
				(type default)
			)
			(layer "F.SilkS")
		)
		(fp_line
			(start 0.7874 0.4064)
			(end -0.7874 0.4064)
			(stroke
				(width 0.1524)
				(type default)
			)
			(layer "F.SilkS")
		)
		(fp_line
			(start -0.7874 0.4064)
			(end -0.7874 -0.4064)
			(stroke
				(width 0.1524)
				(type default)
			)
			(layer "F.SilkS")
		)
		(fp_line
			(start -0.12065 -0.305054)
			(end -0.12065 -0.2794)
			(stroke
				(width 0.1)
				(type default)
			)
			(layer "F.Fab")
		)
		(fp_line
			(start -0.67945 -0.305054)
			(end -0.12065 -0.305054)
			(stroke
				(width 0.1)
				(type default)
			)
			(layer "F.Fab")
		)
		(fp_line
			(start 0.67945 -0.3048)
			(end 0.67945 0.3048)
			(stroke
				(width 0.1)
				(type default)
			)
			(layer "F.Fab")
		)
		(fp_line
			(start 0.12065 -0.3048)
			(end 0.67945 -0.3048)
			(stroke
				(width 0.1)
				(type default)
			)
			(layer "F.Fab")
		)
		(fp_line
			(start 0.12065 -0.2794)
			(end 0.12065 -0.3048)
			(stroke
				(width 0.1)
				(type default)
			)
			(layer "F.Fab")
		)
		(fp_line
			(start -0.12065 -0.2794)
			(end 0.12065 -0.2794)
			(stroke
				(width 0.1)
				(type default)
			)
			(layer "F.Fab")
		)
		(fp_line
			(start 0.120396 0.2794)
			(end -0.12065 0.2794)
			(stroke
				(width 0.1)
				(type default)
			)
			(layer "F.Fab")
		)
		(fp_line
			(start -0.12065 0.2794)
			(end -0.12065 0.3048)
			(stroke
				(width 0.1)
				(type default)
			)
			(layer "F.Fab")
		)
		(fp_line
			(start 0.67945 0.3048)
			(end 0.120396 0.3048)
			(stroke
				(width 0.1)
				(type default)
			)
			(layer "F.Fab")
		)
		(fp_line
			(start 0.120396 0.3048)
			(end 0.120396 0.2794)
			(stroke
				(width 0.1)
				(type default)
			)
			(layer "F.Fab")
		)
		(fp_line
			(start -0.12065 0.3048)
			(end -0.67945 0.3048)
			(stroke
				(width 0.1)
				(type default)
			)
			(layer "F.Fab")
		)
		(fp_line
			(start -0.67945 0.3048)
			(end -0.67945 -0.305054)
			(stroke
				(width 0.1)
				(type default)
			)
			(layer "F.Fab")
		)
		(pad "1" smd circle
			(at -0.40005 0 90)
			(size 0 0)
			(layers "F.Cu" "F.Mask" "F.Paste")
			(net "P3V3_9ZXL045_P0_VDDR")
		)
		(pad "2" smd circle
			(at 0.40005 0 90)
			(size 0 0)
			(layers "F.Cu" "F.Mask" "F.Paste")
			(net "GND")
		)
	)
	(footprint ""
		(layer "F.Cu")
		(at 445.19088 -95.872808 180)
		(property "Reference" "R3601"
			(at 0 0 180)
			(layer "F.SilkS")
			(hide yes)
			(effects
				(font
					(size 1.27 1.27)
				)
			)
		)
		(property "Value" ""
			(at 0 0 180)
			(layer "F.Fab")
			(effects
				(font
					(size 1.27 1.27)
				)
			)
		)
		(duplicate_pad_numbers_are_jumpers no)
		(fp_line
			(start 0.7874 0.4064)
			(end -0.7874 0.4064)
			(stroke
				(width 0.1524)
				(type default)
			)
			(layer "F.SilkS")
		)
		(fp_line
			(start 0.7874 -0.4064)
			(end 0.7874 0.4064)
			(stroke
				(width 0.1524)
				(type default)
			)
			(layer "F.SilkS")
		)
		(fp_line
			(start -0.7874 0.4064)
			(end -0.7874 -0.4064)
			(stroke
				(width 0.1524)
				(type default)
			)
			(layer "F.SilkS")
		)
		(fp_line
			(start -0.7874 -0.4064)
			(end 0.7874 -0.4064)
			(stroke
				(width 0.1524)
				(type default)
			)
			(layer "F.SilkS")
		)
		(fp_line
			(start 0.67945 0.3048)
			(end 0.120396 0.3048)
			(stroke
				(width 0.1)
				(type default)
			)
			(layer "F.Fab")
		)
		(fp_line
			(start 0.67945 -0.3048)
			(end 0.67945 0.3048)
			(stroke
				(width 0.1)
				(type default)
			)
			(layer "F.Fab")
		)
		(fp_line
			(start 0.12065 -0.2794)
			(end 0.12065 -0.3048)
			(stroke
				(width 0.1)
				(type default)
			)
			(layer "F.Fab")
		)
		(fp_line
			(start 0.12065 -0.3048)
			(end 0.67945 -0.3048)
			(stroke
				(width 0.1)
				(type default)
			)
			(layer "F.Fab")
		)
		(fp_line
			(start 0.120396 0.3048)
			(end 0.120396 0.2794)
			(stroke
				(width 0.1)
				(type default)
			)
			(layer "F.Fab")
		)
		(fp_line
			(start 0.120396 0.2794)
			(end -0.12065 0.2794)
			(stroke
				(width 0.1)
				(type default)
			)
			(layer "F.Fab")
		)
		(fp_line
			(start -0.12065 0.3048)
			(end -0.67945 0.3048)
			(stroke
				(width 0.1)
				(type default)
			)
			(layer "F.Fab")
		)
		(fp_line
			(start -0.12065 0.2794)
			(end -0.12065 0.3048)
			(stroke
				(width 0.1)
				(type default)
			)
			(layer "F.Fab")
		)
		(fp_line
			(start -0.12065 -0.2794)
			(end 0.12065 -0.2794)
			(stroke
				(width 0.1)
				(type default)
			)
			(layer "F.Fab")
		)
		(fp_line
			(start -0.12065 -0.305054)
			(end -0.12065 -0.2794)
			(stroke
				(width 0.1)
				(type default)
			)
			(layer "F.Fab")
		)
		(fp_line
			(start -0.67945 0.3048)
			(end -0.67945 -0.305054)
			(stroke
				(width 0.1)
				(type default)
			)
			(layer "F.Fab")
		)
		(fp_line
			(start -0.67945 -0.305054)
			(end -0.12065 -0.305054)
			(stroke
				(width 0.1)
				(type default)
			)
			(layer "F.Fab")
		)
		(pad "1" smd circle
			(at -0.40005 0 180)
			(size 0 0)
			(layers "F.Cu" "F.Mask" "F.Paste")
			(net "SMB_INA230_1_3V3AUX_SDA_R")
		)
		(pad "2" smd circle
			(at 0.40005 0 180)
			(size 0 0)
			(layers "F.Cu" "F.Mask" "F.Paste")
			(net "SMB_INA230_1_3V3AUX_SDA_R1")
		)
	)
)
